(kicad_pcb
	(version 20260206)
	(generator "pcbnew")
	(generator_version "10.0")
	(general
		(thickness 1.6)
		(legacy_teardrops no)
	)
	(paper "A4")
	(title_block
		(title "Bryce Canyon_F.DPB_16315-1-OCP.brd")
		(comment 1 "Bryce Canyon / footprints 690-696 of 2223")
	)
	(layers
		(0 "F.Cu" signal "TOP")
		(4 "In1.Cu" signal "L2GND")
		(6 "In2.Cu" signal "L3")
		(8 "In3.Cu" signal "L4GND")
		(10 "In4.Cu" signal "L5")
		(12 "In5.Cu" signal "L6VCC")
		(14 "In6.Cu" signal "L7VCC")
		(16 "In7.Cu" signal "L8")
		(18 "In8.Cu" signal "L9GND")
		(20 "In9.Cu" signal "L10")
		(22 "In10.Cu" signal "L11GND")
		(2 "B.Cu" signal "BOTTOM")
		(9 "F.Adhes" user "F.Adhesive")
		(11 "B.Adhes" user "B.Adhesive")
		(13 "F.Paste" user "Package Geometry/Pastemask Top")
		(15 "B.Paste" user "Package Geometry/Pastemask Bottom")
		(5 "F.SilkS" user "Ref Des/Silkscreen Top")
		(7 "B.SilkS" user "Ref Des/Silkscreen Bottom")
		(1 "F.Mask" user "Board Geometry/Soldermask Top")
		(3 "B.Mask" user "Board Geometry/Soldermask Bottom")
		(17 "Dwgs.User" user "User.Drawings")
		(19 "Cmts.User" user "User.Comments")
		(21 "Eco1.User" user "User.Eco1")
		(23 "Eco2.User" user "User.Eco2")
		(25 "Edge.Cuts" user "Board Geometry/Outline")
		(27 "Margin" user)
		(31 "F.CrtYd" user "Package Geometry/Place Bound Top")
		(29 "B.CrtYd" user "Package Geometry/Place Bound Bottom")
		(35 "F.Fab" user "Ref Des/Assembly Top")
		(33 "B.Fab" user "Ref Des/Assembly Bottom")
	)
	(footprint ""
		(layer "F.Cu")
		(at 410.414978 -242.25377)
		(property "Reference" "R264"
			(at 0 0 0)
			(layer "F.SilkS")
			(hide yes)
			(effects
				(font
					(size 1.27 1.27)
				)
			)
		)
		(property "Value" "91R3F-1-GP"
			(at -0.0254 -2.5146 0)
			(unlocked yes)
			(layer "F.Fab")
			(hide yes)
			(effects
				(font
					(size 1.016 1.016)
					(thickness 0.1524)
				)
			)
		)
		(property "Device Type" "R603H22"
			(at -0.0254 -4.0386 0)
			(unlocked yes)
			(layer "F.Fab")
			(hide yes)
			(effects
				(font
					(size 1.016 1.016)
					(thickness 0.1524)
				)
			)
		)
		(duplicate_pad_numbers_are_jumpers no)
		(fp_line
			(start -0.4826 0)
			(end -0.2032 0)
			(stroke
				(width 0.2032)
				(type default)
			)
			(layer "F.SilkS")
		)
		(fp_line
			(start 0.2032 0)
			(end 0.4826 0)
			(stroke
				(width 0.2032)
				(type default)
			)
			(layer "F.SilkS")
		)
		(fp_rect
			(start -0.5842 1.3335)
			(end 0.5842 -1.3335)
			(stroke
				(width 0)
				(type default)
			)
			(fill no)
			(layer "F.CrtYd")
		)
		(fp_rect
			(start -0.5842 1.3335)
			(end 0.5842 -1.3335)
			(stroke
				(width 0)
				(type default)
			)
			(fill no)
			(layer "F.Fab")
		)
		(pad "1" smd custom
			(at 0 -0.762)
			(size 0.2159 0.2159)
			(layers "F.Cu" "F.Mask" "F.Paste")
			(net "P5V_A_3")
			(options
				(clearance outline)
				(anchor circle)
			)
			(primitives
				(gr_poly
					(pts
						(arc
							(start -0.3302 -0.4318)
							(mid -0.402042 -0.402042)
							(end -0.4318 -0.3302)
						)
						(arc
							(start -0.4318 0.3302)
							(mid -0.402042 0.402042)
							(end -0.3302 0.4318)
						)
						(arc
							(start 0.3302 0.4318)
							(mid 0.402042 0.402042)
							(end 0.4318 0.3302)
						)
						(arc
							(start 0.4318 -0.3302)
							(mid 0.402042 -0.402042)
							(end 0.3302 -0.4318)
						)
					)
					(width 0)
					(fill yes)
				)
			)
		)
		(pad "2" smd custom
			(at 0 0.762)
			(size 0.2159 0.2159)
			(layers "F.Cu" "F.Mask" "F.Paste")
			(net "DRV_ACT_9")
			(options
				(clearance outline)
				(anchor circle)
			)
			(primitives
				(gr_poly
					(pts
						(arc
							(start -0.3302 -0.4318)
							(mid -0.402042 -0.402042)
							(end -0.4318 -0.3302)
						)
						(arc
							(start -0.4318 0.3302)
							(mid -0.402042 0.402042)
							(end -0.3302 0.4318)
						)
						(arc
							(start 0.3302 0.4318)
							(mid 0.402042 0.402042)
							(end 0.4318 0.3302)
						)
						(arc
							(start 0.4318 -0.3302)
							(mid 0.402042 -0.402042)
							(end 0.3302 -0.4318)
						)
					)
					(width 0)
					(fill yes)
				)
			)
		)
	)
	(footprint ""
		(layer "F.Cu")
		(at 336.804 -292.016942)
		(property "Reference" "Q38"
			(at 0 0 0)
			(layer "F.SilkS")
			(hide yes)
			(effects
				(font
					(size 1.27 1.27)
				)
			)
		)
		(property "Value" "AO4407AL-GP"
			(at -3.707384 -1.5367 0)
			(unlocked yes)
			(layer "F.Fab")
			(hide yes)
			(effects
				(font
					(size 1.016 1.016)
					(thickness 0.1524)
				)
			)
		)
		(property "Device Type" "SOIC8H69"
			(at -3.707384 -3.0607 0)
			(unlocked yes)
			(layer "F.Fab")
			(hide yes)
			(effects
				(font
					(size 1.016 1.016)
					(thickness 0.1524)
				)
			)
		)
		(duplicate_pad_numbers_are_jumpers no)
		(fp_line
			(start -2.7432 -1.4224)
			(end -2.7432 1.4224)
			(stroke
				(width 0.1524)
				(type default)
			)
			(layer "F.SilkS")
		)
		(fp_line
			(start -2.7432 1.4224)
			(end -2.6416 1.4224)
			(stroke
				(width 0.1524)
				(type default)
			)
			(layer "F.SilkS")
		)
		(fp_line
			(start -2.7432 1.4224)
			(end 2.1336 1.4224)
			(stroke
				(width 0.1524)
				(type default)
			)
			(layer "F.SilkS")
		)
		(fp_line
			(start -2.7178 -0.508)
			(end -2.1844 -0.0508)
			(stroke
				(width 0.1524)
				(type default)
			)
			(layer "F.SilkS")
		)
		(fp_line
			(start -2.6289 3.4417)
			(end -2.6289 1.4732)
			(stroke
				(width 0.381)
				(type default)
			)
			(layer "F.SilkS")
		)
		(fp_line
			(start -2.1844 -0.0508)
			(end -2.7178 0.508)
			(stroke
				(width 0.1524)
				(type default)
			)
			(layer "F.SilkS")
		)
		(fp_line
			(start 2.1336 -1.4224)
			(end -2.7432 -1.4224)
			(stroke
				(width 0.1524)
				(type default)
			)
			(layer "F.SilkS")
		)
		(fp_line
			(start 2.1336 1.4224)
			(end 2.1336 -1.4224)
			(stroke
				(width 0.1524)
				(type default)
			)
			(layer "F.SilkS")
		)
		(fp_poly
			(pts
				(xy -2.2098 -1.4224) (xy -2.2098 1.4224) (xy 2.2098 1.4224) (xy 2.2098 -1.4224)
			)
			(stroke
				(width 0)
				(type default)
			)
			(fill yes)
			(layer "F.SilkS")
		)
		(fp_rect
			(start -2.450084 2.999994)
			(end 2.450084 -2.999994)
			(stroke
				(width 0)
				(type default)
			)
			(fill no)
			(layer "F.CrtYd")
		)
		(fp_poly
			(pts
				(xy -2.8194 3.6322) (xy -2.8194 -3.6322) (xy 2.8194 -3.6322) (xy 2.8194 1.18364) (xy 2.450084 1.18364)
				(xy 2.450084 -2.999994) (xy -2.450084 -2.999994) (xy -2.450084 2.999994) (xy 2.450084 2.999994)
				(xy 2.450084 1.18618) (xy 2.8194 1.18618) (xy 2.8194 3.6322)
			)
			(stroke
				(width 0)
				(type default)
			)
			(fill no)
			(layer "F.CrtYd")
		)
		(fp_rect
			(start -2.8194 3.6322)
			(end 2.8194 -3.6322)
			(stroke
				(width 0)
				(type default)
			)
			(fill no)
			(layer "F.Fab")
		)
		(pad "1" smd rect
			(at -1.905 2.54)
			(size 0.635 1.651)
			(layers "F.Cu" "F.Mask" "F.Paste")
			(net "P12V_A")
		)
		(pad "2" smd rect
			(at -0.635 2.54)
			(size 0.635 1.651)
			(layers "F.Cu" "F.Mask" "F.Paste")
			(net "P12V_A")
		)
		(pad "3" smd rect
			(at 0.635 2.54)
			(size 0.635 1.651)
			(layers "F.Cu" "F.Mask" "F.Paste")
			(net "P12V_A")
		)
		(pad "4" smd rect
			(at 1.905 2.54)
			(size 0.635 1.651)
			(layers "F.Cu" "F.Mask" "F.Paste")
			(net "SW_HDD_N6")
		)
		(pad "5" smd rect
			(at 1.905 -2.54)
			(size 0.635 1.651)
			(layers "F.Cu" "F.Mask" "F.Paste")
			(net "P12V_HDD6")
		)
		(pad "6" smd rect
			(at 0.635 -2.54)
			(size 0.635 1.651)
			(layers "F.Cu" "F.Mask" "F.Paste")
			(net "P12V_HDD6")
		)
		(pad "7" smd rect
			(at -0.635 -2.54)
			(size 0.635 1.651)
			(layers "F.Cu" "F.Mask" "F.Paste")
			(net "P12V_HDD6")
		)
		(pad "8" smd rect
			(at -1.905 -2.54)
			(size 0.635 1.651)
			(layers "F.Cu" "F.Mask" "F.Paste")
			(net "P12V_HDD6")
		)
	)
	(footprint ""
		(layer "F.Cu")
		(at 172.974 -47.157894 180)
		(property "Reference" "R813"
			(at 0 0 180)
			(layer "F.SilkS")
			(hide yes)
			(effects
				(font
					(size 1.27 1.27)
				)
			)
		)
		(property "Value" "200KR2F-L-GP"
			(at 0.064008 -3.993896 180)
			(unlocked yes)
			(layer "F.Fab")
			(hide yes)
			(effects
				(font
					(size 1.016 1.016)
					(thickness 0.1524)
				)
			)
		)
		(property "Device Type" "R402H16"
			(at 0.064008 -5.517896 180)
			(unlocked yes)
			(layer "F.Fab")
			(hide yes)
			(effects
				(font
					(size 1.016 1.016)
					(thickness 0.1524)
				)
			)
		)
		(duplicate_pad_numbers_are_jumpers no)
		(fp_line
			(start 0.508 -0.9398)
			(end -0.508 -0.9398)
			(stroke
				(width 0.1524)
				(type default)
			)
			(layer "F.SilkS")
		)
		(fp_line
			(start -0.508 -0.9398)
			(end -0.508 0.9398)
			(stroke
				(width 0.1524)
				(type default)
			)
			(layer "F.SilkS")
		)
		(fp_rect
			(start -0.508 0.9398)
			(end 0.508 -0.9398)
			(stroke
				(width 0)
				(type default)
			)
			(fill no)
			(layer "F.CrtYd")
		)
		(fp_rect
			(start -0.508 0.9398)
			(end 0.508 -0.9398)
			(stroke
				(width 0)
				(type default)
			)
			(fill no)
			(layer "F.Fab")
		)
		(pad "1" smd custom
			(at 0 -0.4445 180)
			(size 0.1397 0.1397)
			(layers "F.Cu" "F.Mask" "F.Paste")
			(net "SW_HDD_R29")
			(options
				(clearance outline)
				(anchor circle)
			)
			(primitives
				(gr_poly
					(pts
						(arc
							(start -0.1778 -0.2794)
							(mid -0.249642 -0.249642)
							(end -0.2794 -0.1778)
						)
						(arc
							(start -0.2794 0.1778)
							(mid -0.249642 0.249642)
							(end -0.1778 0.2794)
						)
						(arc
							(start 0.1778 0.2794)
							(mid 0.249642 0.249642)
							(end 0.2794 0.1778)
						)
						(arc
							(start 0.2794 -0.1778)
							(mid 0.249642 -0.249642)
							(end 0.1778 -0.2794)
						)
					)
					(width 0)
					(fill yes)
				)
			)
		)
		(pad "2" smd custom
			(at 0 0.4445 180)
			(size 0.1397 0.1397)
			(layers "F.Cu" "F.Mask" "F.Paste")
			(net "SW_HDD_N29")
			(options
				(clearance outline)
				(anchor circle)
			)
			(primitives
				(gr_poly
					(pts
						(arc
							(start -0.1778 -0.2794)
							(mid -0.249642 -0.249642)
							(end -0.2794 -0.1778)
						)
						(arc
							(start -0.2794 0.1778)
							(mid -0.249642 0.249642)
							(end -0.1778 0.2794)
						)
						(arc
							(start 0.1778 0.2794)
							(mid 0.249642 0.249642)
							(end 0.2794 0.1778)
						)
						(arc
							(start 0.2794 -0.1778)
							(mid 0.249642 -0.249642)
							(end 0.1778 -0.2794)
						)
					)
					(width 0)
					(fill yes)
				)
			)
		)
	)
	(footprint ""
		(layer "F.Cu")
		(at 67.347846 -177.169318 -90)
		(property "Reference" "R429"
			(at 0 0 270)
			(layer "F.SilkS")
			(hide yes)
			(effects
				(font
					(size 1.27 1.27)
				)
			)
		)
		(property "Value" "10KR2F-2-GP"
			(at 0.064008 -3.993896 270)
			(unlocked yes)
			(layer "F.Fab")
			(hide yes)
			(effects
				(font
					(size 1.016 1.016)
					(thickness 0.1524)
				)
			)
		)
		(property "Device Type" "R402H16"
			(at 0.064008 -5.517896 270)
			(unlocked yes)
			(layer "F.Fab")
			(hide yes)
			(effects
				(font
					(size 1.016 1.016)
					(thickness 0.1524)
				)
			)
		)
		(duplicate_pad_numbers_are_jumpers no)
		(fp_line
			(start -0.508 -0.9398)
			(end -0.508 0.9398)
			(stroke
				(width 0.1524)
				(type default)
			)
			(layer "F.SilkS")
		)
		(fp_line
			(start 0.508 -0.9398)
			(end -0.508 -0.9398)
			(stroke
				(width 0.1524)
				(type default)
			)
			(layer "F.SilkS")
		)
		(fp_rect
			(start -0.508 0.9398)
			(end 0.508 -0.9398)
			(stroke
				(width 0)
				(type default)
			)
			(fill no)
			(layer "F.CrtYd")
		)
		(fp_rect
			(start -0.508 0.9398)
			(end 0.508 -0.9398)
			(stroke
				(width 0)
				(type default)
			)
			(fill no)
			(layer "F.Fab")
		)
		(pad "1" smd custom
			(at 0 -0.4445 270)
			(size 0.1397 0.1397)
			(layers "F.Cu" "F.Mask" "F.Paste")
			(net "P3V3_STBY_A")
			(options
				(clearance outline)
				(anchor circle)
			)
			(primitives
				(gr_poly
					(pts
						(arc
							(start -0.1778 -0.2794)
							(mid -0.249642 -0.249642)
							(end -0.2794 -0.1778)
						)
						(arc
							(start -0.2794 0.1778)
							(mid -0.249642 0.249642)
							(end -0.1778 0.2794)
						)
						(arc
							(start 0.1778 0.2794)
							(mid 0.249642 0.249642)
							(end 0.2794 0.1778)
						)
						(arc
							(start 0.2794 -0.1778)
							(mid 0.249642 -0.249642)
							(end 0.1778 -0.2794)
						)
					)
					(width 0)
					(fill yes)
				)
			)
		)
		(pad "2" smd custom
			(at 0 0.4445 270)
			(size 0.1397 0.1397)
			(layers "F.Cu" "F.Mask" "F.Paste")
			(net "HDD_PRSNT_13")
			(options
				(clearance outline)
				(anchor circle)
			)
			(primitives
				(gr_poly
					(pts
						(arc
							(start -0.1778 -0.2794)
							(mid -0.249642 -0.249642)
							(end -0.2794 -0.1778)
						)
						(arc
							(start -0.2794 0.1778)
							(mid -0.249642 0.249642)
							(end -0.1778 0.2794)
						)
						(arc
							(start 0.1778 0.2794)
							(mid 0.249642 0.249642)
							(end 0.2794 0.1778)
						)
						(arc
							(start 0.2794 -0.1778)
							(mid 0.249642 -0.249642)
							(end 0.1778 -0.2794)
						)
					)
					(width 0)
					(fill yes)
				)
			)
		)
	)
	(footprint ""
		(layer "F.Cu")
		(at 17.145 -242.25377)
		(property "Reference" "R195"
			(at 0 0 0)
			(layer "F.SilkS")
			(hide yes)
			(effects
				(font
					(size 1.27 1.27)
				)
			)
		)
		(property "Value" "130R3F-GP"
			(at -0.0254 -2.5146 0)
			(unlocked yes)
			(layer "F.Fab")
			(hide yes)
			(effects
				(font
					(size 1.016 1.016)
					(thickness 0.1524)
				)
			)
		)
		(property "Device Type" "R603H22"
			(at -0.0254 -4.0386 0)
			(unlocked yes)
			(layer "F.Fab")
			(hide yes)
			(effects
				(font
					(size 1.016 1.016)
					(thickness 0.1524)
				)
			)
		)
		(duplicate_pad_numbers_are_jumpers no)
		(fp_line
			(start -0.4826 0)
			(end -0.2032 0)
			(stroke
				(width 0.2032)
				(type default)
			)
			(layer "F.SilkS")
		)
		(fp_line
			(start 0.2032 0)
			(end 0.4826 0)
			(stroke
				(width 0.2032)
				(type default)
			)
			(layer "F.SilkS")
		)
		(fp_rect
			(start -0.5842 1.3335)
			(end 0.5842 -1.3335)
			(stroke
				(width 0)
				(type default)
			)
			(fill no)
			(layer "F.CrtYd")
		)
		(fp_rect
			(start -0.5842 1.3335)
			(end 0.5842 -1.3335)
			(stroke
				(width 0)
				(type default)
			)
			(fill no)
			(layer "F.Fab")
		)
		(pad "1" smd custom
			(at 0 -0.762)
			(size 0.2159 0.2159)
			(layers "F.Cu" "F.Mask" "F.Paste")
			(net "P5V_A_1")
			(options
				(clearance outline)
				(anchor circle)
			)
			(primitives
				(gr_poly
					(pts
						(arc
							(start -0.3302 -0.4318)
							(mid -0.402042 -0.402042)
							(end -0.4318 -0.3302)
						)
						(arc
							(start -0.4318 0.3302)
							(mid -0.402042 0.402042)
							(end -0.3302 0.4318)
						)
						(arc
							(start 0.3302 0.4318)
							(mid 0.402042 0.402042)
							(end 0.4318 0.3302)
						)
						(arc
							(start 0.4318 -0.3302)
							(mid 0.402042 -0.402042)
							(end 0.3302 -0.4318)
						)
					)
					(width 0)
					(fill yes)
				)
			)
		)
		(pad "2" smd custom
			(at 0 0.762)
			(size 0.2159 0.2159)
			(layers "F.Cu" "F.Mask" "F.Paste")
			(net "FLT_HDD0")
			(options
				(clearance outline)
				(anchor circle)
			)
			(primitives
				(gr_poly
					(pts
						(arc
							(start -0.3302 -0.4318)
							(mid -0.402042 -0.402042)
							(end -0.4318 -0.3302)
						)
						(arc
							(start -0.4318 0.3302)
							(mid -0.402042 0.402042)
							(end -0.3302 0.4318)
						)
						(arc
							(start 0.3302 0.4318)
							(mid 0.402042 0.402042)
							(end 0.4318 0.3302)
						)
						(arc
							(start 0.4318 -0.3302)
							(mid 0.402042 -0.402042)
							(end 0.3302 -0.4318)
						)
					)
					(width 0)
					(fill yes)
				)
			)
		)
	)
	(footprint ""
		(layer "F.Cu")
		(at 433.359052 -172.851318 90)
		(property "Reference" "C322"
			(at 0 0 90)
			(layer "F.SilkS")
			(hide yes)
			(effects
				(font
					(size 1.27 1.27)
				)
			)
		)
		(property "Value" "SCD033U25V2KX-GP"
			(at 1.1811 -2.7051 90)
			(unlocked yes)
			(layer "F.Fab")
			(hide yes)
			(effects
				(font
					(size 1.016 1.016)
					(thickness 0.1524)
				)
			)
		)
		(property "Device Type" "C402H22"
			(at 1.1811 -4.2291 90)
			(unlocked yes)
			(layer "F.Fab")
			(hide yes)
			(effects
				(font
					(size 1.016 1.016)
					(thickness 0.1524)
				)
			)
		)
		(duplicate_pad_numbers_are_jumpers no)
		(fp_rect
			(start -0.4318 0.9525)
			(end 0.4318 -0.9525)
			(stroke
				(width 0)
				(type default)
			)
			(fill no)
			(layer "F.CrtYd")
		)
		(fp_rect
			(start -0.4318 0.9525)
			(end 0.4318 -0.9525)
			(stroke
				(width 0)
				(type default)
			)
			(fill no)
			(layer "F.Fab")
		)
		(pad "1" smd custom
			(at 0 -0.4445 90)
			(size 0.1524 0.1524)
			(layers "F.Cu" "F.Mask" "F.Paste")
			(net "P12V_A")
			(options
				(clearance outline)
				(anchor circle)
			)
			(primitives
				(gr_poly
					(pts
						(arc
							(start 0.3048 -0.2032)
							(mid 0.275042 -0.275042)
							(end 0.2032 -0.3048)
						)
						(arc
							(start -0.2032 -0.3048)
							(mid -0.275042 -0.275042)
							(end -0.3048 -0.2032)
						)
						(arc
							(start -0.3048 0.2032)
							(mid -0.275042 0.275042)
							(end -0.2032 0.3048)
						)
						(arc
							(start 0.2032 0.3048)
							(mid 0.275042 0.275042)
							(end 0.3048 0.2032)
						)
					)
					(width 0)
					(fill yes)
				)
			)
		)
		(pad "2" smd custom
			(at 0 0.4445 90)
			(size 0.1524 0.1524)
			(layers "F.Cu" "F.Mask" "F.Paste")
			(net "SW_HDD_N21")
			(options
				(clearance outline)
				(anchor circle)
			)
			(primitives
				(gr_poly
					(pts
						(arc
							(start 0.3048 -0.2032)
							(mid 0.275042 -0.275042)
							(end 0.2032 -0.3048)
						)
						(arc
							(start -0.2032 -0.3048)
							(mid -0.275042 -0.275042)
							(end -0.3048 -0.2032)
						)
						(arc
							(start -0.3048 0.2032)
							(mid -0.275042 0.275042)
							(end -0.2032 0.3048)
						)
						(arc
							(start 0.2032 0.3048)
							(mid 0.275042 0.275042)
							(end 0.3048 0.2032)
						)
					)
					(width 0)
					(fill yes)
				)
			)
		)
	)
	(footprint ""
		(layer "F.Cu")
		(at 280.549858 -414.221168)
		(property "Reference" ""
			(at 0 0 0)
			(layer "F.SilkS")
			(hide yes)
			(effects
				(font
					(size 1.27 1.27)
				)
			)
		)
		(property "Value" "*"
			(at -5.3594 -1.1811 0)
			(unlocked yes)
			(layer "F.Fab")
			(hide yes)
			(effects
				(font
					(size 1.016 1.016)
					(thickness 0.1524)
				)
			)
		)
		(duplicate_pad_numbers_are_jumpers no)
		(fp_poly
			(pts
				(arc
					(start 4.064 0)
					(mid -4.064 0)
					(end 4.064 0)
				)
			)
			(stroke
				(width 0)
				(type default)
			)
			(fill no)
			(layer "B.CrtYd")
		)
		(fp_poly
			(pts
				(arc
					(start 4.064 0)
					(mid -4.064 0)
					(end 4.064 0)
				)
			)
			(stroke
				(width 0)
				(type default)
			)
			(fill no)
			(layer "F.CrtYd")
		)
		(fp_poly
			(pts
				(arc
					(start 4.064 0)
					(mid -4.064 0)
					(end 4.064 0)
				)
			)
			(stroke
				(width 0)
				(type default)
			)
			(fill no)
			(layer "B.Fab")
		)
		(fp_poly
			(pts
				(arc
					(start 4.064 0)
					(mid -4.064 0)
					(end 4.064 0)
				)
			)
			(stroke
				(width 0)
				(type default)
			)
			(fill no)
			(layer "F.Fab")
		)
		(pad "1" thru_hole circle
			(at 0 0)
			(size 7.5184 7.5184)
			(drill 3.5052)
			(layers "*.Cu" "*.Mask")
			(remove_unused_layers no)
			(net "Net_62")
			(clearance -1.4986)
			(thermal_gap 0.3048)
			(padstack
				(mode front_inner_back)
				(layer "Inner"
					(shape circle)
					(size 3.9116 3.9116)
					(clearance 0.3048)
				)
				(layer "B.Cu"
					(shape circle)
					(size 7.5184 7.5184)
					(clearance -1.4986)
				)
			)
		)
	)
)
